# BASEBOARD_FAB2 (Tioga Pass) — schematic netlist excerpt (pin names and nets, part order shuffled) for the footprints in the layout excerpt that follows; sources: Cadence DE-HDL packaged netlist, KiCad conversion of Wiwynn_Tioga_Pass_MB.brd

R7G8  RES  2.26K 1.0% CHIP  pkg 0402  page 215 : A = VR_PVDDQ_ABC_XADDR1 ; B = GND
C5A6  CAP_A  47UF 4V 20% X5R  pkg 0603V  page 220 : A = PVDDQ_DEF ; B = GND
C8F1  CAP  2200PF 50V 10% X7R  pkg 0402LF  page 241 : A = VR_P5V_STBY_RC_COMP ; B = AGND_P5V_STBY

(kicad_pcb
	(version 20260206)
	(generator "pcbnew")
	(generator_version "10.0")
	(general
		(thickness 1.6)
		(legacy_teardrops no)
	)
	(paper "A4")
	(title_block
		(title "Wiwynn_Tioga_Pass_MB.brd")
		(comment 1 "Tioga Pass / footprints 1568-1570 of 4770")
	)
	(layers
		(0 "F.Cu" signal "TOP")
		(4 "In1.Cu" signal "L2GND")
		(6 "In2.Cu" signal "L3")
		(8 "In3.Cu" signal "L4GND")
		(10 "In4.Cu" signal "L5")
		(12 "In5.Cu" signal "L6GND")
		(14 "In6.Cu" signal "L7VCC")
		(16 "In7.Cu" signal "L8VCC")
		(18 "In8.Cu" signal "L9GND")
		(20 "In9.Cu" signal "L10")
		(22 "In10.Cu" signal "L11GND")
		(24 "In11.Cu" signal "L12")
		(26 "In12.Cu" signal "L13GND")
		(2 "B.Cu" signal "BOTTOM")
		(9 "F.Adhes" user "F.Adhesive")
		(11 "B.Adhes" user "B.Adhesive")
		(13 "F.Paste" user "Package Geometry/Pastemask Top")
		(15 "B.Paste" user "Package Geometry/Pastemask Bottom")
		(5 "F.SilkS" user "Ref Des/Silkscreen Top")
		(7 "B.SilkS" user "Ref Des/Silkscreen Bottom")
		(1 "F.Mask" user "Board Geometry/Soldermask Top")
		(3 "B.Mask" user "Board Geometry/Soldermask Bottom")
		(17 "Dwgs.User" user "User.Drawings")
		(19 "Cmts.User" user "User.Comments")
		(21 "Eco1.User" user "User.Eco1")
		(23 "Eco2.User" user "User.Eco2")
		(25 "Edge.Cuts" user "Board Geometry/Outline")
		(27 "Margin" user)
		(31 "F.CrtYd" user "Package Geometry/Place Bound Top")
		(29 "B.CrtYd" user "Package Geometry/Place Bound Bottom")
		(35 "F.Fab" user "Ref Des/Assembly Top")
		(33 "B.Fab" user "Ref Des/Assembly Bottom")
	)
	(footprint ""
		(layer "F.Cu")
		(at 393.674346 -64.172338 -90)
		(property "Reference" "C8F1"
			(at 0 0 270)
			(layer "F.SilkS")
			(hide yes)
			(effects
				(font
					(size 1.27 1.27)
				)
			)
		)
		(property "Value" ""
			(at 0 0 270)
			(layer "F.Fab")
			(effects
				(font
					(size 1.27 1.27)
				)
			)
		)
		(duplicate_pad_numbers_are_jumpers no)
		(fp_poly
			(pts
				(xy 0.3048 -0.1016) (xy 0.3048 0.9906) (xy -0.3048 0.9906) (xy -0.3048 -0.1016)
			)
			(stroke
				(width 0)
				(type default)
			)
			(fill no)
			(layer "F.CrtYd")
		)
		(fp_line
			(start -0.3048 0.9906)
			(end 0.3048 0.9906)
			(stroke
				(width 0.1)
				(type default)
			)
			(layer "F.Fab")
		)
		(fp_line
			(start 0.3048 0.9906)
			(end 0.3048 -0.1016)
			(stroke
				(width 0.1)
				(type default)
			)
			(layer "F.Fab")
		)
		(fp_line
			(start -0.3048 -0.1016)
			(end -0.3048 0.9906)
			(stroke
				(width 0.1)
				(type default)
			)
			(layer "F.Fab")
		)
		(fp_line
			(start 0.3048 -0.1016)
			(end -0.3048 -0.1016)
			(stroke
				(width 0.1)
				(type default)
			)
			(layer "F.Fab")
		)
		(pad "1" smd rect
			(at 0 0 270)
			(size 0.508 0.508)
			(layers "F.Cu" "F.Mask" "F.Paste")
			(net "VR_P5V_STBY_RC_COMP")
		)
		(pad "2" smd rect
			(at 0 0.889 270)
			(size 0.508 0.508)
			(layers "F.Cu" "F.Mask" "F.Paste")
			(net "AGND_P5V_STBY")
		)
		(zone
			(layer "F.Cu")
			(hatch none 0.5)
			(connect_pads
				(clearance 0)
			)
			(min_thickness 0.25)
			(keepout
				(tracks not_allowed)
				(vias allowed)
				(pads allowed)
				(copperpour not_allowed)
				(footprints allowed)
			)
			(placement
				(enabled no)
				(sheetname "")
			)
			(fill
				(thermal_gap 0.5)
				(thermal_bridge_width 0.5)
				(island_removal_mode 0)
			)
			(polygon
				(pts
					(xy 393.039346 -64.426338) (xy 393.039346 -63.918338) (xy 393.420346 -63.918338) (xy 393.420346 -64.426338)
				)
			)
		)
		(zone
			(layer "F.Cu")
			(hatch none 0.5)
			(connect_pads
				(clearance 0)
			)
			(min_thickness 0.25)
			(keepout
				(tracks allowed)
				(vias not_allowed)
				(pads allowed)
				(copperpour not_allowed)
				(footprints allowed)
			)
			(placement
				(enabled no)
				(sheetname "")
			)
			(fill
				(thermal_gap 0.5)
				(thermal_bridge_width 0.5)
				(island_removal_mode 0)
			)
			(polygon
				(pts
					(xy 393.420346 -64.426338) (xy 393.420346 -63.918338) (xy 393.039346 -63.918338) (xy 393.039346 -64.426338)
				)
			)
		)
	)
	(footprint ""
		(layer "F.Cu")
		(at 266.397232 -149.8092 90)
		(property "Reference" "C5A6"
			(at 1.848866 0.752348 90)
			(unlocked yes)
			(layer "F.SilkS")
			(effects
				(font
					(size 1.27 0.9652)
					(thickness 0.1524)
				)
			)
		)
		(property "Value" ""
			(at 0 0 90)
			(layer "F.Fab")
			(effects
				(font
					(size 1.27 1.27)
				)
			)
		)
		(duplicate_pad_numbers_are_jumpers no)
		(fp_rect
			(start -0.500126 1.598422)
			(end 0.500126 -0.201422)
			(stroke
				(width 0)
				(type default)
			)
			(fill no)
			(layer "F.CrtYd")
		)
		(fp_line
			(start 0.500126 -0.201422)
			(end 0.500126 1.598422)
			(stroke
				(width 0.1)
				(type default)
			)
			(layer "F.Fab")
		)
		(fp_line
			(start -0.500126 -0.201422)
			(end 0.500126 -0.201422)
			(stroke
				(width 0.1)
				(type default)
			)
			(layer "F.Fab")
		)
		(fp_line
			(start 0.500126 1.598422)
			(end -0.500126 1.598422)
			(stroke
				(width 0.1)
				(type default)
			)
			(layer "F.Fab")
		)
		(fp_line
			(start -0.500126 1.598422)
			(end -0.500126 -0.201422)
			(stroke
				(width 0.1)
				(type default)
			)
			(layer "F.Fab")
		)
		(pad "1" smd rect
			(at 0 0)
			(size 0.889 0.9906)
			(layers "F.Cu" "F.Mask" "F.Paste")
			(net "PVDDQ_DEF")
		)
		(pad "2" smd rect
			(at 0 1.397)
			(size 0.889 0.9906)
			(layers "F.Cu" "F.Mask" "F.Paste")
			(net "GND")
		)
		(zone
			(layer "F.Cu")
			(hatch none 0.5)
			(connect_pads
				(clearance 0)
			)
			(min_thickness 0.25)
			(keepout
				(tracks not_allowed)
				(vias allowed)
				(pads allowed)
				(copperpour not_allowed)
				(footprints allowed)
			)
			(placement
				(enabled no)
				(sheetname "")
			)
			(fill
				(thermal_gap 0.5)
				(thermal_bridge_width 0.5)
				(island_removal_mode 0)
			)
			(polygon
				(pts
					(xy 267.349732 -149.3139) (xy 267.349732 -150.3045) (xy 266.841732 -150.3045) (xy 266.841732 -149.3139)
				)
			)
		)
		(zone
			(layer "F.Cu")
			(hatch none 0.5)
			(connect_pads
				(clearance 0)
			)
			(min_thickness 0.25)
			(keepout
				(tracks allowed)
				(vias not_allowed)
				(pads allowed)
				(copperpour not_allowed)
				(footprints allowed)
			)
			(placement
				(enabled no)
				(sheetname "")
			)
			(fill
				(thermal_gap 0.5)
				(thermal_bridge_width 0.5)
				(island_removal_mode 0)
			)
			(polygon
				(pts
					(xy 267.349732 -149.3139) (xy 267.349732 -150.3045) (xy 266.841732 -150.3045) (xy 266.841732 -149.3139)
				)
			)
		)
	)
	(footprint ""
		(layer "F.Cu")
		(at 349.123 -14.859 90)
		(property "Reference" "R7G8"
			(at 0 0 90)
			(layer "F.SilkS")
			(hide yes)
			(effects
				(font
					(size 1.27 1.27)
				)
			)
		)
		(property "Value" ""
			(at 0 0 90)
			(layer "F.Fab")
			(effects
				(font
					(size 1.27 1.27)
				)
			)
		)
		(duplicate_pad_numbers_are_jumpers no)
		(fp_poly
			(pts
				(xy -0.2794 -0.1016) (xy 0.2794 -0.1016) (xy 0.2794 0.9906) (xy -0.2794 0.9906)
			)
			(stroke
				(width 0)
				(type default)
			)
			(fill no)
			(layer "F.CrtYd")
		)
		(fp_line
			(start 0.2794 -0.1016)
			(end -0.2794 -0.1016)
			(stroke
				(width 0.1)
				(type default)
			)
			(layer "F.Fab")
		)
		(fp_line
			(start -0.2794 -0.1016)
			(end -0.2794 0.9906)
			(stroke
				(width 0.1)
				(type default)
			)
			(layer "F.Fab")
		)
		(fp_line
			(start 0.2794 0.9906)
			(end 0.2794 -0.1016)
			(stroke
				(width 0.1)
				(type default)
			)
			(layer "F.Fab")
		)
		(fp_line
			(start -0.2794 0.9906)
			(end 0.2794 0.9906)
			(stroke
				(width 0.1)
				(type default)
			)
			(layer "F.Fab")
		)
		(pad "1" smd rect
			(at 0 0 90)
			(size 0.508 0.508)
			(layers "F.Cu" "F.Mask" "F.Paste")
			(net "VR_PVDDQ_ABC_XADDR1")
		)
		(pad "2" smd rect
			(at 0 0.889 90)
			(size 0.508 0.508)
			(layers "F.Cu" "F.Mask" "F.Paste")
			(net "GND")
		)
		(zone
			(layer "F.Cu")
			(hatch none 0.5)
			(connect_pads
				(clearance 0)
			)
			(min_thickness 0.25)
			(keepout
				(tracks allowed)
				(vias not_allowed)
				(pads allowed)
				(copperpour not_allowed)
				(footprints allowed)
			)
			(placement
				(enabled no)
				(sheetname "")
			)
			(fill
				(thermal_gap 0.5)
				(thermal_bridge_width 0.5)
				(island_removal_mode 0)
			)
			(polygon
				(pts
					(xy 349.377 -14.605) (xy 349.377 -15.113) (xy 349.758 -15.113) (xy 349.758 -14.605)
				)
			)
		)
		(zone
			(layer "F.Cu")
			(hatch none 0.5)
			(connect_pads
				(clearance 0)
			)
			(min_thickness 0.25)
			(keepout
				(tracks not_allowed)
				(vias allowed)
				(pads allowed)
				(copperpour not_allowed)
				(footprints allowed)
			)
			(placement
				(enabled no)
				(sheetname "")
			)
			(fill
				(thermal_gap 0.5)
				(thermal_bridge_width 0.5)
				(island_removal_mode 0)
			)
			(polygon
				(pts
					(xy 349.758 -14.605) (xy 349.758 -15.113) (xy 349.377 -15.113) (xy 349.377 -14.605)
				)
			)
		)
	)
)
